(kicad_pcb
	(version 20241229)
	(generator "pcbnew")
	(generator_version "9.0")
	(general
		(thickness 1.63)
		(legacy_teardrops no)
	)
	(paper "A4")
	(title_block
		(title "CM4 Baseboard")
		(date "2026-01-05")
		(rev "1.1.1")
		(company "Antmicro Ltd")
		(comment 1 "www.antmicro.com")
		(comment 9 "footprints 137-137 of 506")
	)
	(layers
		(0 "F.Cu" signal)
		(4 "In1.Cu" power)
		(6 "In2.Cu" power)
		(8 "In3.Cu" signal)
		(10 "In4.Cu" signal)
		(2 "B.Cu" signal)
		(9 "F.Adhes" user "F.Adhesive")
		(11 "B.Adhes" user "B.Adhesive")
		(13 "F.Paste" user)
		(15 "B.Paste" user)
		(5 "F.SilkS" user "F.Silkscreen")
		(7 "B.SilkS" user "B.Silkscreen")
		(1 "F.Mask" user)
		(3 "B.Mask" user)
		(17 "Dwgs.User" user "User.Drawings")
		(19 "Cmts.User" user "User.Comments")
		(21 "Eco1.User" user "User.Eco1")
		(23 "Eco2.User" user "User.Eco2")
		(25 "Edge.Cuts" user)
		(27 "Margin" user)
		(31 "F.CrtYd" user "F.Courtyard")
		(29 "B.CrtYd" user "B.Courtyard")
		(35 "F.Fab" user)
		(33 "B.Fab" user)
	)
	(footprint "antmicro-footprints:Conn_Socket_Samtec_ERF5_2x20_ERF5-020-05.0-L-DV-K-TR"
		(layer "F.Cu")
		(at 138.417962 145.7165 90)
		(property "Reference" "J801"
			(at 5.13 -4.53 90)
			(layer "F.SilkS")
			(effects
				(font
					(size 0.7 0.7)
					(thickness 0.15)
				)
				(justify left bottom)
			)
		)
		(property "Value" "Socket_Samtec_ERF5_2x20_ERF5-020-05.0-L-DV-K-TR"
			(at 0 3.9 90)
			(layer "F.Fab")
			(effects
				(font
					(size 0.7 0.7)
					(thickness 0.15)
				)
				(justify left bottom)
			)
		)
		(property "Datasheet" "https://suddendocs.samtec.com/productspecs/erm5-erf5.pdf?_gl=1*1g914su*_ga*MTE0MzExNjY4MC4xNjcyMTQ5NTUz*_ga_3KFNZC07WW*MTY3Mjg0NzY5Ny42LjEuMTY3Mjg0ODE3MS42MC4wLjA."
			(at 0 0 90)
			(layer "F.Fab")
			(hide yes)
			(effects
				(font
					(size 1.27 1.27)
					(thickness 0.15)
				)
			)
		)
		(property "MPN" "ERF5-020-05.0-L-DV-K-TR"
			(at 0 0 90)
			(unlocked yes)
			(layer "F.Fab")
			(hide yes)
			(effects
				(font
					(size 1 1)
					(thickness 0.15)
				)
			)
		)
		(property "Manufacturer" "Samtec"
			(at 0 0 90)
			(unlocked yes)
			(layer "F.Fab")
			(hide yes)
			(effects
				(font
					(size 1 1)
					(thickness 0.15)
				)
			)
		)
		(property "Author" "Antmicro"
			(at 0 0 90)
			(unlocked yes)
			(layer "F.Fab")
			(hide yes)
			(effects
				(font
					(size 1 1)
					(thickness 0.15)
				)
			)
		)
		(property "License" "Apache-2.0"
			(at 0 0 90)
			(unlocked yes)
			(layer "F.Fab")
			(hide yes)
			(effects
				(font
					(size 1 1)
					(thickness 0.15)
				)
			)
		)
		(property "Pitch" "0.5 mm"
			(at 0 0 90)
			(unlocked yes)
			(layer "F.Fab")
			(hide yes)
			(effects
				(font
					(size 1 1)
					(thickness 0.15)
				)
			)
		)
		(sheetname "/Peripherals/")
		(sheetfile "peripherals.kicad_sch")
		(attr smd)
		(fp_line
			(start 8.401 -2.475)
			(end 8.401 2.476)
			(stroke
				(width 0.15)
				(type solid)
			)
			(layer "F.SilkS")
		)
		(fp_line
			(start 5.351 -2.475)
			(end 8.401 -2.475)
			(stroke
				(width 0.15)
				(type solid)
			)
			(layer "F.SilkS")
		)
		(fp_line
			(start -8.4 -2.475)
			(end -5.349 -2.475)
			(stroke
				(width 0.15)
				(type solid)
			)
			(layer "F.SilkS")
		)
		(fp_line
			(start 8.401 2.476)
			(end 5.351 2.476)
			(stroke
				(width 0.15)
				(type solid)
			)
			(layer "F.SilkS")
		)
		(fp_line
			(start -5.349 2.476)
			(end -8.4 2.476)
			(stroke
				(width 0.15)
				(type solid)
			)
			(layer "F.SilkS")
		)
		(fp_line
			(start -8.4 2.476)
			(end -8.4 -2.475)
			(stroke
				(width 0.15)
				(type solid)
			)
			(layer "F.SilkS")
		)
		(fp_circle
			(center -5.2 2.9)
			(end -5.25 2.9)
			(stroke
				(width 0.15)
				(type solid)
			)
			(fill no)
			(layer "F.SilkS")
		)
		(fp_poly
			(pts
				(xy 4.877 -1.225) (xy 4.624 -1.225) (xy 4.624 -2.725) (xy 4.877 -2.725)
			)
			(stroke
				(width 0.01)
				(type solid)
			)
			(fill yes)
			(layer "F.Paste")
		)
		(fp_poly
			(pts
				(xy 4.377 -1.225) (xy 4.124 -1.225) (xy 4.124 -2.725) (xy 4.377 -2.725)
			)
			(stroke
				(width 0.01)
				(type solid)
			)
			(fill yes)
			(layer "F.Paste")
		)
		(fp_poly
			(pts
				(xy 3.878 -1.225) (xy 3.625 -1.225) (xy 3.625 -2.725) (xy 3.878 -2.725)
			)
			(stroke
				(width 0.01)
				(type solid)
			)
			(fill yes)
			(layer "F.Paste")
		)
		(fp_poly
			(pts
				(xy 3.378 -1.225) (xy 3.125 -1.225) (xy 3.125 -2.725) (xy 3.378 -2.725)
			)
			(stroke
				(width 0.01)
				(type solid)
			)
			(fill yes)
			(layer "F.Paste")
		)
		(fp_poly
			(pts
				(xy 2.878 -1.225) (xy 2.625 -1.225) (xy 2.625 -2.725) (xy 2.878 -2.725)
			)
			(stroke
				(width 0.01)
				(type solid)
			)
			(fill yes)
			(layer "F.Paste")
		)
		(fp_poly
			(pts
				(xy 2.378 -1.225) (xy 2.125 -1.225) (xy 2.125 -2.725) (xy 2.378 -2.725)
			)
			(stroke
				(width 0.01)
				(type solid)
			)
			(fill yes)
			(layer "F.Paste")
		)
		(fp_poly
			(pts
				(xy 1.877 -1.225) (xy 1.623 -1.225) (xy 1.623 -2.725) (xy 1.877 -2.725)
			)
			(stroke
				(width 0.01)
				(type solid)
			)
			(fill yes)
			(layer "F.Paste")
		)
		(fp_poly
			(pts
				(xy 1.377 -1.225) (xy 1.123 -1.225) (xy 1.123 -2.725) (xy 1.377 -2.725)
			)
			(stroke
				(width 0.01)
				(type solid)
			)
			(fill yes)
			(layer "F.Paste")
		)
		(fp_poly
			(pts
				(xy 0.877 -1.225) (xy 0.623 -1.225) (xy 0.623 -2.725) (xy 0.877 -2.725)
			)
			(stroke
				(width 0.01)
				(type solid)
			)
			(fill yes)
			(layer "F.Paste")
		)
		(fp_poly
			(pts
				(xy 0.377 -1.225) (xy 0.123 -1.225) (xy 0.123 -2.725) (xy 0.377 -2.725)
			)
			(stroke
				(width 0.01)
				(type solid)
			)
			(fill yes)
			(layer "F.Paste")
		)
		(fp_poly
			(pts
				(xy -0.121 -1.225) (xy -0.375 -1.225) (xy -0.375 -2.725) (xy -0.121 -2.725)
			)
			(stroke
				(width 0.01)
				(type solid)
			)
			(fill yes)
			(layer "F.Paste")
		)
		(fp_poly
			(pts
				(xy -0.621 -1.225) (xy -0.875 -1.225) (xy -0.875 -2.725) (xy -0.621 -2.725)
			)
			(stroke
				(width 0.01)
				(type solid)
			)
			(fill yes)
			(layer "F.Paste")
		)
		(fp_poly
			(pts
				(xy -1.122 -1.225) (xy -1.376 -1.225) (xy -1.376 -2.725) (xy -1.122 -2.725)
			)
			(stroke
				(width 0.01)
				(type solid)
			)
			(fill yes)
			(layer "F.Paste")
		)
		(fp_poly
			(pts
				(xy -1.622 -1.225) (xy -1.876 -1.225) (xy -1.876 -2.725) (xy -1.622 -2.725)
			)
			(stroke
				(width 0.01)
				(type solid)
			)
			(fill yes)
			(layer "F.Paste")
		)
		(fp_poly
			(pts
				(xy -2.123 -1.225) (xy -2.375 -1.225) (xy -2.375 -2.725) (xy -2.123 -2.725)
			)
			(stroke
				(width 0.01)
				(type solid)
			)
			(fill yes)
			(layer "F.Paste")
		)
		(fp_poly
			(pts
				(xy -2.623 -1.225) (xy -2.875 -1.225) (xy -2.875 -2.725) (xy -2.623 -2.725)
			)
			(stroke
				(width 0.01)
				(type solid)
			)
			(fill yes)
			(layer "F.Paste")
		)
		(fp_poly
			(pts
				(xy -3.123 -1.225) (xy -3.375 -1.225) (xy -3.375 -2.725) (xy -3.123 -2.725)
			)
			(stroke
				(width 0.01)
				(type solid)
			)
			(fill yes)
			(layer "F.Paste")
		)
		(fp_poly
			(pts
				(xy -3.623 -1.225) (xy -3.875 -1.225) (xy -3.875 -2.725) (xy -3.623 -2.725)
			)
			(stroke
				(width 0.01)
				(type solid)
			)
			(fill yes)
			(layer "F.Paste")
		)
		(fp_poly
			(pts
				(xy -4.123 -1.225) (xy -4.376 -1.225) (xy -4.376 -2.725) (xy -4.123 -2.725)
			)
			(stroke
				(width 0.01)
				(type solid)
			)
			(fill yes)
			(layer "F.Paste")
		)
		(fp_poly
			(pts
				(xy -4.623 -1.225) (xy -4.876 -1.225) (xy -4.876 -2.725) (xy -4.623 -2.725)
			)
			(stroke
				(width 0.01)
				(type solid)
			)
			(fill yes)
			(layer "F.Paste")
		)
		(fp_poly
			(pts
				(xy 4.877 2.726) (xy 4.624 2.726) (xy 4.624 1.226) (xy 4.877 1.226)
			)
			(stroke
				(width 0.01)
				(type solid)
			)
			(fill yes)
			(layer "F.Paste")
		)
		(fp_poly
			(pts
				(xy 4.377 2.726) (xy 4.124 2.726) (xy 4.124 1.226) (xy 4.377 1.226)
			)
			(stroke
				(width 0.01)
				(type solid)
			)
			(fill yes)
			(layer "F.Paste")
		)
		(fp_poly
			(pts
				(xy 3.878 2.726) (xy 3.625 2.726) (xy 3.625 1.226) (xy 3.878 1.226)
			)
			(stroke
				(width 0.01)
				(type solid)
			)
			(fill yes)
			(layer "F.Paste")
		)
		(fp_poly
			(pts
				(xy 3.378 2.726) (xy 3.125 2.726) (xy 3.125 1.226) (xy 3.378 1.226)
			)
			(stroke
				(width 0.01)
				(type solid)
			)
			(fill yes)
			(layer "F.Paste")
		)
		(fp_poly
			(pts
				(xy 2.878 2.726) (xy 2.625 2.726) (xy 2.625 1.226) (xy 2.878 1.226)
			)
			(stroke
				(width 0.01)
				(type solid)
			)
			(fill yes)
			(layer "F.Paste")
		)
		(fp_poly
			(pts
				(xy 2.378 2.726) (xy 2.125 2.726) (xy 2.125 1.226) (xy 2.378 1.226)
			)
			(stroke
				(width 0.01)
				(type solid)
			)
			(fill yes)
			(layer "F.Paste")
		)
		(fp_poly
			(pts
				(xy 1.877 2.726) (xy 1.623 2.726) (xy 1.623 1.226) (xy 1.877 1.226)
			)
			(stroke
				(width 0.01)
				(type solid)
			)
			(fill yes)
			(layer "F.Paste")
		)
		(fp_poly
			(pts
				(xy 1.377 2.726) (xy 1.123 2.726) (xy 1.123 1.226) (xy 1.377 1.226)
			)
			(stroke
				(width 0.01)
				(type solid)
			)
			(fill yes)
			(layer "F.Paste")
		)
		(fp_poly
			(pts
				(xy 0.877 2.726) (xy 0.623 2.726) (xy 0.623 1.226) (xy 0.877 1.226)
			)
			(stroke
				(width 0.01)
				(type solid)
			)
			(fill yes)
			(layer "F.Paste")
		)
		(fp_poly
			(pts
				(xy 0.377 2.726) (xy 0.123 2.726) (xy 0.123 1.226) (xy 0.377 1.226)
			)
			(stroke
				(width 0.01)
				(type solid)
			)
			(fill yes)
			(layer "F.Paste")
		)
		(fp_poly
			(pts
				(xy -0.121 2.726) (xy -0.375 2.726) (xy -0.375 1.226) (xy -0.121 1.226)
			)
			(stroke
				(width 0.01)
				(type solid)
			)
			(fill yes)
			(layer "F.Paste")
		)
		(fp_poly
			(pts
				(xy -0.621 2.726) (xy -0.875 2.726) (xy -0.875 1.226) (xy -0.621 1.226)
			)
			(stroke
				(width 0.01)
				(type solid)
			)
			(fill yes)
			(layer "F.Paste")
		)
		(fp_poly
			(pts
				(xy -1.122 2.726) (xy -1.376 2.726) (xy -1.376 1.226) (xy -1.122 1.226)
			)
			(stroke
				(width 0.01)
				(type solid)
			)
			(fill yes)
			(layer "F.Paste")
		)
		(fp_poly
			(pts
				(xy -1.622 2.726) (xy -1.876 2.726) (xy -1.876 1.226) (xy -1.622 1.226)
			)
			(stroke
				(width 0.01)
				(type solid)
			)
			(fill yes)
			(layer "F.Paste")
		)
		(fp_poly
			(pts
				(xy -2.123 2.726) (xy -2.375 2.726) (xy -2.375 1.226) (xy -2.123 1.226)
			)
			(stroke
				(width 0.01)
				(type solid)
			)
			(fill yes)
			(layer "F.Paste")
		)
		(fp_poly
			(pts
				(xy -2.623 2.726) (xy -2.875 2.726) (xy -2.875 1.226) (xy -2.623 1.226)
			)
			(stroke
				(width 0.01)
				(type solid)
			)
			(fill yes)
			(layer "F.Paste")
		)
		(fp_poly
			(pts
				(xy -3.123 2.726) (xy -3.375 2.726) (xy -3.375 1.226) (xy -3.123 1.226)
			)
			(stroke
				(width 0.01)
				(type solid)
			)
			(fill yes)
			(layer "F.Paste")
		)
		(fp_poly
			(pts
				(xy -3.623 2.726) (xy -3.875 2.726) (xy -3.875 1.226) (xy -3.623 1.226)
			)
			(stroke
				(width 0.01)
				(type solid)
			)
			(fill yes)
			(layer "F.Paste")
		)
		(fp_poly
			(pts
				(xy -4.123 2.726) (xy -4.376 2.726) (xy -4.376 1.226) (xy -4.123 1.226)
			)
			(stroke
				(width 0.01)
				(type solid)
			)
			(fill yes)
			(layer "F.Paste")
		)
		(fp_poly
			(pts
				(xy -4.623 2.726) (xy -4.876 2.726) (xy -4.876 1.226) (xy -4.623 1.226)
			)
			(stroke
				(width 0.01)
				(type solid)
			)
			(fill yes)
			(layer "F.Paste")
		)
		(fp_rect
			(start 8.651 2.926)
			(end -8.65 -2.925)
			(stroke
				(width 0.05)
				(type solid)
			)
			(fill no)
			(layer "F.CrtYd")
		)
		(fp_line
			(start -8.39 1.35)
			(end -7.27 2.47)
			(stroke
				(width 0.15)
				(type solid)
			)
			(layer "F.Fab")
		)
		(fp_rect
			(start 8.401 2.476)
			(end -8.4 -2.475)
			(stroke
				(width 0.15)
				(type solid)
			)
			(fill no)
			(layer "F.Fab")
		)
		(fp_text user "${REFERENCE}"
			(at -9.401 8.008 90)
			(layer "F.Fab")
			(effects
				(font
					(size 0.7 0.7)
					(thickness 0.15)
				)
				(justify left bottom)
			)
		)
		(fp_text user "Author: Antmicro"
			(at -9.401 5.608 90)
			(layer "F.Fab")
			(effects
				(font
					(size 0.7 0.7)
					(thickness 0.15)
				)
				(justify left bottom)
			)
		)
		(fp_text user "License: Apache-2.0"
			(at -9.401 6.808 90)
			(layer "F.Fab")
			(effects
				(font
					(size 0.7 0.7)
					(thickness 0.15)
				)
				(justify left bottom)
			)
		)
		(pad "" np_thru_hole circle
			(at -6.9 1.401 270)
			(size 1.45 1.45)
			(drill 1.45)
			(layers "*.Cu" "*.Mask")
		)
		(pad "" np_thru_hole circle
			(at 6.901 1.401 270)
			(size 1.45 1.45)
			(drill 1.45)
			(layers "*.Cu" "*.Mask")
		)
		(pad "1" smd rect
			(at -4.748 1.976)
			(size 1.5 0.3)
			(layers "F.Cu" "F.Mask")
			(net 9 "+3V3")
			(pintype "passive")
		)
		(pad "2" smd rect
			(at -4.748 -1.975)
			(size 1.5 0.3)
			(layers "F.Cu" "F.Mask")
			(net 10 "+5V")
			(pintype "passive")
		)
		(pad "3" smd rect
			(at -4.248 1.976)
			(size 1.5 0.3)
			(layers "F.Cu" "F.Mask")
			(net 243 "/Compute module/GPIO.2")
			(pintype "passive")
		)
		(pad "4" smd rect
			(at -4.248 -1.975)
			(size 1.5 0.3)
			(layers "F.Cu" "F.Mask")
			(net 10 "+5V")
			(pintype "passive")
		)
		(pad "5" smd rect
			(at -3.749 1.976)
			(size 1.5 0.3)
			(layers "F.Cu" "F.Mask")
			(net 242 "/Compute module/GPIO.3")
			(pintype "passive")
		)
		(pad "6" smd rect
			(at -3.749 -1.975)
			(size 1.5 0.3)
			(layers "F.Cu" "F.Mask")
			(net 3 "GND")
			(pintype "passive")
		)
		(pad "7" smd rect
			(at -3.249 1.976)
			(size 1.5 0.3)
			(layers "F.Cu" "F.Mask")
			(net 240 "/Compute module/GPIO.4{slash}TXD3")
			(pintype "passive")
		)
		(pad "8" smd rect
			(at -3.249 -1.975)
			(size 1.5 0.3)
			(layers "F.Cu" "F.Mask")
			(net 239 "/Compute module/GPIO.14{slash}RXD0")
			(pintype "passive")
		)
		(pad "9" smd rect
			(at -2.749 1.976)
			(size 1.5 0.3)
			(layers "F.Cu" "F.Mask")
			(net 3 "GND")
			(pintype "passive")
		)
		(pad "10" smd rect
			(at -2.749 -1.975)
			(size 1.5 0.3)
			(layers "F.Cu" "F.Mask")
			(net 241 "/Compute module/GPIO.15{slash}TXD0")
			(pintype "passive")
		)
		(pad "11" smd rect
			(at -2.249 1.976)
			(size 1.5 0.3)
			(layers "F.Cu" "F.Mask")
			(net 238 "/Compute module/GPIO.17")
			(pintype "passive")
		)
		(pad "12" smd rect
			(at -2.249 -1.975)
			(size 1.5 0.3)
			(layers "F.Cu" "F.Mask")
			(net 237 "/Compute module/GPIO.18")
			(pintype "passive")
		)
		(pad "13" smd rect
			(at -1.749 1.976)
			(size 1.5 0.3)
			(layers "F.Cu" "F.Mask")
			(net 236 "/Compute module/GPIO.27")
			(pintype "passive")
		)
		(pad "14" smd rect
			(at -1.749 -1.975)
			(size 1.5 0.3)
			(layers "F.Cu" "F.Mask")
			(net 251 "/Compute module/GPIO.AIN1")
			(pintype "passive")
		)
		(pad "15" smd rect
			(at -1.249 1.976)
			(size 1.5 0.3)
			(layers "F.Cu" "F.Mask")
			(net 234 "/Compute module/GPIO.22")
			(pintype "passive")
		)
		(pad "16" smd rect
			(at -1.249 -1.975)
			(size 1.5 0.3)
			(layers "F.Cu" "F.Mask")
			(net 235 "/Compute module/GPIO.23")
			(pintype "passive")
		)
		(pad "17" smd rect
			(at -0.748 1.976)
			(size 1.5 0.3)
			(layers "F.Cu" "F.Mask")
			(net 9 "+3V3")
			(pintype "passive")
		)
		(pad "18" smd rect
			(at -0.748 -1.975)
			(size 1.5 0.3)
			(layers "F.Cu" "F.Mask")
			(net 233 "/Compute module/GPIO.24")
			(pintype "passive")
		)
		(pad "19" smd rect
			(at -0.248 1.976)
			(size 1.5 0.3)
			(layers "F.Cu" "F.Mask")
			(net 232 "/Compute module/GPIO.10")
			(pintype "passive")
		)
		(pad "20" smd rect
			(at -0.248 -1.975)
			(size 1.5 0.3)
			(layers "F.Cu" "F.Mask")
			(net 3 "GND")
			(pintype "passive")
		)
		(pad "21" smd rect
			(at 0.25 1.976)
			(size 1.5 0.3)
			(layers "F.Cu" "F.Mask")
			(net 229 "/Compute module/GPIO.9{slash}RXD4")
			(pintype "passive")
		)
		(pad "22" smd rect
			(at 0.25 -1.975)
			(size 1.5 0.3)
			(layers "F.Cu" "F.Mask")
			(net 230 "/Compute module/GPIO.25")
			(pintype "passive")
		)
		(pad "23" smd rect
			(at 0.75 1.976)
			(size 1.5 0.3)
			(layers "F.Cu" "F.Mask")
			(net 227 "/Compute module/GPIO.11")
			(pintype "passive")
		)
		(pad "24" smd rect
			(at 0.75 -1.975)
			(size 1.5 0.3)
			(layers "F.Cu" "F.Mask")
			(net 228 "/Compute module/GPIO.8{slash}TXD4")
			(pintype "passive")
		)
		(pad "25" smd rect
			(at 1.25 1.976)
			(size 1.5 0.3)
			(layers "F.Cu" "F.Mask")
			(net 3 "GND")
			(pintype "passive")
		)
		(pad "26" smd rect
			(at 1.25 -1.975)
			(size 1.5 0.3)
			(layers "F.Cu" "F.Mask")
			(net 226 "/Compute module/GPIO.7")
			(pintype "passive")
		)
		(pad "27" smd rect
			(at 1.75 1.976)
			(size 1.5 0.3)
			(layers "F.Cu" "F.Mask")
			(net 447 "/Compute module/GPIO.0{slash}SDA0")
			(pintype "passive")
		)
		(pad "28" smd rect
			(at 1.75 -1.975)
			(size 1.5 0.3)
			(layers "F.Cu" "F.Mask")
			(net 446 "/Compute module/GPIO.1{slash}SCL0")
			(pintype "passive")
		)
		(pad "29" smd rect
			(at 2.25 1.976)
			(size 1.5 0.3)
			(layers "F.Cu" "F.Mask")
			(net 225 "/Compute module/GPIO.5{slash}RXD3")
			(pintype "passive")
		)
		(pad "30" smd rect
			(at 2.25 -1.975)
			(size 1.5 0.3)
			(layers "F.Cu" "F.Mask")
			(net 253 "/Compute module/GPIO.AIN0")
			(pintype "passive")
		)
		(pad "31" smd rect
			(at 2.75 1.976)
			(size 1.5 0.3)
			(layers "F.Cu" "F.Mask")
			(net 223 "/Compute module/GPIO.6")
			(pintype "passive")
		)
		(pad "32" smd rect
			(at 2.75 -1.975)
			(size 1.5 0.3)
			(layers "F.Cu" "F.Mask")
			(net 224 "/Compute module/GPIO.12{slash}RXD5")
			(pintype "passive")
		)
		(pad "33" smd rect
			(at 3.25 1.976)
			(size 1.5 0.3)
			(layers "F.Cu" "F.Mask")
			(net 221 "/Compute module/GPIO.13{slash}TXD5")
			(pintype "passive")
		)
		(pad "34" smd rect
			(at 3.25 -1.975)
			(size 1.5 0.3)
			(layers "F.Cu" "F.Mask")
			(net 3 "GND")
			(pintype "passive")
		)
		(pad "35" smd rect
			(at 3.75 1.976)
			(size 1.5 0.3)
			(layers "F.Cu" "F.Mask")
			(net 219 "/Compute module/GPIO.19")
			(pintype "passive")
		)
		(pad "36" smd rect
			(at 3.75 -1.975)
			(size 1.5 0.3)
			(layers "F.Cu" "F.Mask")
			(net 222 "/Compute module/GPIO.16")
			(pintype "passive")
		)
		(pad "37" smd rect
			(at 4.25 1.976)
			(size 1.5 0.3)
			(layers "F.Cu" "F.Mask")
			(net 217 "/Compute module/GPIO.26")
			(pintype "passive")
		)
		(pad "38" smd rect
			(at 4.25 -1.975)
			(size 1.5 0.3)
			(layers "F.Cu" "F.Mask")
			(net 220 "/Compute module/GPIO.20")
			(pintype "passive")
		)
		(pad "39" smd rect
			(at 4.75 1.976)
			(size 1.5 0.3)
			(layers "F.Cu" "F.Mask")
			(net 3 "GND")
			(pintype "passive")
		)
		(pad "40" smd rect
			(at 4.75 -1.975)
			(size 1.5 0.3)
			(layers "F.Cu" "F.Mask")
			(net 218 "/Compute module/GPIO.21")
			(pintype "passive")
		)
	)
)
